# FCB BOM.xlsx — Honey Badger FCB BOM (bom)
| Level | Parent Number | Part Number | Description | Green Factor | Life Cycle State | Manufacturer | Manufacturer Part Number | Source | BOM Usage | M/P Code | S/D | Qty | UoM | Location |
| 1 | 91.64W10.A31G | 55.64W02.A21G | KNOX FCB(DIP) | N/A; | Released |  |  |  | M | Manufacture |  | 1 | PCS |  |
| 2 | 55.64W02.A21G | 06.1BETB.14Z | LED RED/BLUE LTL1BETBEK5H149-WN | R2_SA; | Released | LITEON | LTL1BETBEK5H149-WN | Single |  | Purchase | DIP | 6 | PCS | LED1 LED2 LED3 LED4 LED5 LED6 |
| 2 | 55.64W02.A21G | 20.81943.024 | CONN CTR 4P+20S ST 51952-220LF ,PA66 | R2_SA; | Released | FCI | 51952-220LF | Multiple |  | Purchase | DIP | 2 | PCS | CN10 CN9 |
| 2 | 55.64W02.A21G | 21.61427.105 | HEAD ML 1R5P RT A2541WR0-1TX5 ,NYLON6T | R2_SA; | Released | JWT | A2541WR0-1TX5PA-6T | Single |  | Purchase | DIP | 6 | PCS | CN1 CN2 CN3 CN4 CN5 CN6 |
| 2 | 55.64W02.A21G | 21.61942.103 | HAED ML 3P 21S-H91-03GB31 W/JUMPER G/F | R2_SA;HF_SA; | Released | PINREX | 21S-H91-03GB31 | Single |  | Purchase | DIP | 1 | PCS | JP1 |
| 2 | 55.64W02.A21G | 21.63033.103 | HEAD ML 1R3P ST 210-91-03GB01 ,PA9T | R2_SA; | Released | PINREX | 210-91-03GB01 | Multiple |  | Purchase | DIP | 1 | PCS | CN8 |
| 2 | 55.64W02.A21G | 40.58D03.001 | LBL POLYIMIDE31.8*6.35 BARCODE | R2_SA;HF_SA;G_SA; | Released | LABELJET | 40.58D03.001 | Single |  | Purchase | DIP | 2 | PCS |  |
| 2 | 55.64W02.A21G | 40.64W19.001 | LBL YELLOW KNOX 25.5X12.8MM FOR KNOX | R2_SA; | Released | TBD |  | Single |  | Purchase | DIP | 1 | PCS |  |
| 2 | 55.64W02.A21G | 42.64W15.001 | HLDR FAN CONN 1 HU230 | R2_SA; | Released | TBD |  | Single |  | Purchase | DIP | 6 | PCS |  |
| 2 | 55.64W02.A21G | 55.64W02.MA5G | KNOX FAN CONTROLLER BOARD(SMT) | N/A; | Released |  |  |  | M | Manufacture | DIP | 1 | PCS |  |
| 3 | 55.64W02.MA5G | 084.00925.003N | FET MOS PH0925CL NC LFPAK 4P | R2_SA; | Released | NXP | PH0925CL | Single |  | Purchase | SMT | 8 | PCS | PQ1 PQ11 PQ12 PQ13 PQ2 PQ3 PQ7 PQ8 |
| 3 | 55.64W02.MA5G | 34.64W05.001 | BOSS NUT H1.2 M4 | R2_SA; | Released | TBD |  | Single |  | Purchase | SMT | 5 | PCS | H10 H11 H12 H13 H9 |
| 3 | 55.64W02.MA5G | 48.64W04.01M | PCB 12433-1M KNOX_FAN CONTROL BD 4L GCE | R2_SA; | Released | TBD |  | Multiple |  | Purchase | SMT | 1 | PCS |  |
| 3 | 55.64W02.MA5G | 63.00000.00L | CHIP RES 0 J 1/10W 0603 | R2_SA;HF_SA;G_SA; | Released | TA-I ; RALEC ; YAGEO ; WALSIN | RM06JTN0 ; RTT03000JTP ; RC0603JR-070RL ; WR06X000PTL | Multiple |  | Purchase | SMT | 1 | PCS | PR54 |
| 3 | 55.64W02.MA5G | 63.10134.1DL | CHIP RES 100 J 1/16W 0402 | R2_SA;HF_SA;G_SA; | Released | TA-I;RALEC;CYNTEC;YAGEO;WALSIN | RM04JTN101 ; RTT02101JTH ; RR0510S-101-JN ; RC0402JR-07100RL;WR04X101JTL | Multiple |  | Purchase | SMT | 2 | PCS | R360 R361 |
| 3 | 55.64W02.MA5G | 63.10333.15L | CHIP RES 10K J 1/10W 0603 | R2_SA;HF_SA;G_SA; | Released | RALEC;TA-I;YAGEO;WALSIN | RTT03103JTP;RM06JTN103;RC0603JR-0710KL;WR06X103JTL | Multiple |  | Purchase | SMT | 1 | PCS | PR53 |
| 3 | 55.64W02.MA5G | 63.10334.1DL | CHIP RES 10K J 1/16W 0402 | R2_SA;HF_SA;G_SA; | Released | CYNTEC;RALEC;TA-I;WALSIN;YAGEO | RR0510S-103-JN;RTT02103JTH;RM04JTN103;WR04X103JTL;RC0402JR-0710KL | Multiple |  | Purchase | SMT | 1 | PCS | R261 |
| 3 | 55.64W02.MA5G | 63.10434.1DL | CHIP RES 100K J 1/16W 0402 | R2_SA;HF_SA;G_SA; | Released | TA-I;RALEC;CYNTEC;YAGEO;WALSIN | RM04JTN104 ; RTT02104JTH ; RR0510S-104-JN ; RC0402JR-07100KL;WR04X104JTL | Multiple |  | Purchase | SMT | 1 | PCS | R11 |
| 3 | 55.64W02.MA5G | 63.10534.1DL | CHIP RES 1M J 1/16W 0402 | R2_SA;HF_SA;G_SA; | Released | TA-I;RALEC;CYNTEC;YAGEO;WALSIN | RM04JTN105 ; RTT02105JTH ; RR0510S-105-JN ; RC0402JR-071ML;WR04X105JTL | Multiple |  | Purchase | SMT | 1 | PCS | R10 |
| 3 | 55.64W02.MA5G | 63.10634.1DL | CHIP RES 10M J 1/16W 0402 | R2_SA;HF_SA;G_SA; | Released | TA-I;RALEC;CYNTEC;YAGEO;WALSIN | RM04JTN106 ; RTT02106JTH ; RR0510S-106-JN ; RC0402JR-0710ML;WR04X106JTL | Multiple |  | Purchase | SMT | 1 | PCS | R365 |
| 3 | 55.64W02.MA5G | 63.15231.16L | CHIP RES 1.5K J 1/8W 0805(ROHS | R2_SA;HF_SA;G_SA; | Released | TAI;YAGEO;RALEC | RM10JTN152;RC0805JR-071K5L;RTT05152JTP | Multiple |  | Purchase | SMT | 1 | PCS | PR43 |
| 3 | 55.64W02.MA5G | 63.18232.11L | CHIP RES 1.8K J 1/4W 1206 | R2_SA;HF_SA;G_SA; | Released | RALEC ; TA-I ; YAGEO | RTT06182JTP ; RM12JTN182 ; RC1206JR-071K8L | Multiple |  | Purchase | SMT | 6 | PCS | R122 R123 R124 R125 R126 R127 |
| 3 | 55.64W02.MA5G | 63.33134.1DL | CHIP RES 330 J 1/16W 0402 | R2_SA;HF_SA;G_SA; | Released | TA-I;RALEC;CYNTEC;YAGEO;WALSIN | RM04JTN331 ; RTT02331JTH ; RR0510S-331-JN ; RC0402JR-07330RL;WR04X331JTL | Multiple |  | Purchase | SMT | 6 | PCS | R129 R148 R149 R155 R156 R157 |
| 3 | 55.64W02.MA5G | 63.47234.1DL | CHIP RES 4.7K J 1/16W 0402 | R2_SA;HF_SA;G_SA; | Released | TA-I;RALEC;CYNTEC;YAGEO;WALSIN | RM04JTN472 ; RTT02472JTH ; RR0510S-472-JN ; RC0402JR-074K7L;WR04X472JTL | Multiple |  | Purchase | SMT | 9 | PCS | PR47 PR49 R39 R43 R44 R48 R54 R55 R56 |
| 3 | 55.64W02.MA5G | 63.47334.1DL | CHIP RES 47K J 1/16W 0402 | R2_SA;HF_SA;G_SA; | Released | TAI;RALEC;CYNTEC;YAGEO;WALSIN | RM04JTN473 ; RTT02473JTH ; RR0510S-473-JN ; RC0402JR-0747KL;WR04X473JTL | Multiple |  | Purchase | SMT | 1 | PCS | R260 |
| 3 | 55.64W02.MA5G | 63.R0031.16L | CHIP RES 0 J 1/8W 0805 | R2_SA;HF_SA;G_SA; | Released | TA-I ; RALEC ; YAGEO ; WALSIN | RM10JTN0 ; RTT05000JTP ; RC0805JR-070RL ; WR08X000PTL | Multiple |  | Purchase | SMT | 1 | PCS | R8 |
| 3 | 55.64W02.MA5G | 63.R0034.1DL | CHIP RES 0 J 1/16W 0402 | R2_SA;HF_SA;G_SA; | Released | TA-I;RALEC;CYNTEC;YAGEO;WALSIN | RM04JTN0;RTT02000JTH;RR0510X-000-XN;RC0402JR-070RL;WR04X000PTL | Multiple |  | Purchase | SMT | 42 | PCS | PR14 PR94 PR95 PR96 PR97 R1 R106 R107 R108 R109 R136 R137 R138 R139 R140 R141 R164 R165 R171 R172 R173 R174 R175 R176 R183 R184 R2 R26 R28 R30 R32 R34 R364 R38 R4 R45 R46 R47 R5 R51 R62 R63 |
| 3 | 55.64W02.MA5G | 64.0U505.L0L | CHIP RES 0.0005 F 1W 0612 | R2_SA; | Released | VISHAY;CYNTEC | WSK0612L5000FEA;RL1632L4-0R5M-FN | Multiple |  | Purchase | SMT | 3 | PCS | PR29 PR30 PR31 |
| 3 | 55.64W02.MA5G | 64.10005.6DL | CHIP RES 100 F 1/16W 0402 | R2_SA;HF_SA;G_SA; | Released | TA-I ; RALEC ; CYNTEC ; YAGEO;WALSIN | RM04FTN1000 ; RTT021000FTH ; RR0510S-1000-FN ; RC0402FR-07100RL;WR04X1000FTL | Multiple |  | Purchase | SMT | 2 | PCS | PR101 PR99 |
| 3 | 55.64W02.MA5G | 64.10015.6DL | CHIP RES 1K F 1/16W 0402 | R2_SA;HF_SA;G_SA; | Released | TA-I;RALEC;CYNTEC;YAGEO;WALSIN | RM04FTN1001 ; RTT021001FTH ; RR0510S-102-FN ; RC0402FR-071KL;WR04X1001FTL | Multiple |  | Purchase | SMT | 6 | PCS | PR106 PR107 PR16 PR38 PR41 PR7 |
| 3 | 55.64W02.MA5G | 64.10025.6DL | CHIP RES 10K F 1/16W 0402 | R2_SA;HF_SA;G_SA; | Released | TA-I;RALEC;CYNTEC;YAGEO;WALSIN | RM04FTN1002 ; RTT021002FTH ; RR0510S-103-FN ; RC0402FR-0710KL;WR04X1002FTL | Multiple |  | Purchase | SMT | 20 | PCS | PR45 PR58 R102 R103 R104 R105 R128 R15 R35 R359 R366 R367 R74 R75 R76 R77 R88 R89 R90 R91 |
| 3 | 55.64W02.MA5G | 64.10035.6DL | CHIP RES 100K F 1/16W 0402 | R2_SA;HF_SA;G_SA; | Released | TA-I;RALEC;CYNTEC;YAGEO;WALSIN | RM04FTN1003 ; RTT021003FTH ; RR0510S-104-FN ; RC0402FR-07100KL;WR04X1003FTL | Multiple |  | Purchase | SMT | 7 | PCS | PR1 PR55 PR6 R17 R18 R19 R21 |
| 3 | 55.64W02.MA5G | 64.10R05.6DL | CHIP RES 10 F 1/16W 0402 | R2_SA;HF_SA;G_SA; | Released | TA-I ; RALEC ; CYNTEC ; YAGEO | RM04FTN10R0 ; RTT0210R0FTH ; RR0510S-100-FN ; RC0402FR-0710RL | Multiple |  | Purchase | SMT | 17 | PCS | PR102 PR103 PR118 PR119 PR18 PR19 PR2 PR20 PR21 PR22 PR23 PR26 PR27 PR28 PR51 R150 R151 |
| 3 | 55.64W02.MA5G | 64.11025.6DL | CHIP RES 11K F 1/16W 0402 | R2_SA;HF_SA;G_SA; | Released | TA-I ; RALEC ; CYNTEC ; YAGEO;WALSIN | RM04FTN1102 ; RTT021102FTH ; RR0510S-1102-FN ; RC0402FR-0711KL;WR04X1102FTL | Multiple |  | Purchase | SMT | 1 | PCS | PR8 |
| 3 | 55.64W02.MA5G | 64.11035.L0L | CHIP RES 110K F 1/16W 0402 | R2_SA;HF_SA;G_SA; | Released | TA-I;RALEC;CYNTEC | RM04FTN1103;RTT021103FTH;RR0510S-1103-FN | Multiple |  | Purchase | SMT | 3 | PCS | R14 R16 R36 |
| 3 | 55.64W02.MA5G | 64.17835.6DL | CHIP RES 178K F 1/16W 0402 | R2_SA;HF_SA;G_SA; | Released | TAI;RALEC;CYNTEC;YAGEO | RM04FTN1783;RTT021783FTH;RR0510S-1783-FN;RC0402FR-07178KL | Multiple |  | Purchase | SMT | 2 | PCS | PR110 PR111 |
| 3 | 55.64W02.MA5G | 64.20015.6DL | CHIP RES 2K F 1/16W 0402 | R2_SA;HF_SA;G_SA; | Released | TA-I;RALEC;CYNTEC;YAGEO;WALSIN | RM04FTN2001 ; RTT022001FTH ; RR0510S-202-FN ; RC0402FR-072KL;WR04X2001FTL | Multiple |  | Purchase | SMT | 6 | PCS | R111 R113 R115 R117 R119 R121 |
| 3 | 55.64W02.MA5G | 64.20025.6DL | CHIP RES 20K F 1/16W 0402 | R2_SA;HF_SA;G_SA; | Released | TA-I;RALEC;CYNTEC;YAGEO;WALSIN | RM04FTN2002 ; RTT022002FTH ; RR0510S-203-FN ; RC0402FR-0720KL;WR04X2002FTL | Multiple |  | Purchase | SMT | 2 | PCS | PR114 PR115 |
| 3 | 55.64W02.MA5G | 64.22125.55L | CHIP RES 22.1K F 1/10W 0603 | R2_SA;HF_SA;G_SA; | Released | TA-I ; RALEC ; YAGEO | RM06FTN2212 ; RTT032212FTP ; RC0603FR-0722K1L | Multiple |  | Purchase | SMT | 1 | PCS | PR56 |
| 3 | 55.64W02.MA5G | 64.27015.6DL | CHIP RES 2.7K F 1/16W 0402 | R2_SA;HF_SA;G_SA; | Released | TAI;RALEC;CYNTEC;YAGEO | RM04FTN2701;RTT022701FTH;RR0510S-2701-FN;RC0402FR-072K7L | Multiple |  | Purchase | SMT | 2 | PCS | PR104 PR105 |
| 3 | 55.64W02.MA5G | 64.27025.55L | CHIP RES 27K F 1/10W 0603 | R2_SA;HF_SA;G_SA; | Released | TA-I ; RALEC ; YAGEO | RM06FTN2702 ; RTT032702FTP ; RC0603FR-0727KL | Multiple |  | Purchase | SMT | 12 | PCS | R100 R101 R70 R71 R72 R73 R84 R85 R86 R87 R98 R99 |
| 3 | 55.64W02.MA5G | 64.33015.55L | CHIP RES 3.3K F 1/10W 0603(ROH | R2_SA;HF_SA;G_SA; | Released | TAI;RALEC;YAGEO | RM06FTN3301;RTT033301FTP;RC0603FR-073K3L | Multiple |  | Purchase | SMT | 1 | PCS | PR117 |
| 3 | 55.64W02.MA5G | 64.40215.6DL | CHIP RES 4.02K F 1/16W 0402 | R2_SA;HF_SA;G_SA; | Released | TA-I;RALEC;CYNTEC;YAGEO;WALSIN | RM04FTN4021;RTT024021FTH;RR0510S-4021-FN;RC0402FR-074K02L;WR04X4021FTL | Multiple |  | Purchase | SMT | 1 | PCS | PR36 |
| 3 | 55.64W02.MA5G | 64.47005.6DL | CHIP RES 470 F 1/16W 0402 | R2_SA;HF_SA;G_SA; | Released | TA-I;RALEC;CYNTEC;YAGEO | RM04FTN4700;RTT024700FTH;RR0510S-471-FN;RC0402FR-07470RL | Multiple |  | Purchase | SMT | 4 | PCS | R114 R116 R118 R120 |
| 3 | 55.64W02.MA5G | 64.47015.6DL | CHIP RES 4.7K F 1/16W 0402 | R2_SA;HF_SA;G_SA; | Released | TA-I;RALEC;CYNTEC;YAGEO;WALSIN | RM04FTN4701;RTT024701FTH;RR0510S-472-FN;RC0402FR-074K7L;WR04X4701FTL | Multiple |  | Purchase | SMT | 25 | PCS | PR15 PR59 R12 R130 R131 R132 R133 R134 R135 R20 R3 R60 R61 R66 R67 R68 R69 R80 R81 R82 R83 R93 R94 R95 R97 |
| 3 | 55.64W02.MA5G | 64.47025.55L | CHIP RES 47K F 1/10W 0603 | R2_SA;HF_SA;G_SA; | Released | TA-I ; RALEC ; YAGEO | RM06FTN4702 ; RTT034702FTP ; RC0603FR-0747KL | Multiple |  | Purchase | SMT | 1 | PCS | PR52 |
| 3 | 55.64W02.MA5G | 64.49915.6DL | CHIP RES 4.99K F 1/16W 0402 | R2_SA;HF_SA;G_SA; | Released | TA-I;RALEC;CYNTEC;YAGEO;WALSIN | RM04FTN4991 ; RTT024991FTH ; RR0510S-4991-FN ; RC0402FR-074K99L ; WR04X4991FTL | Multiple |  | Purchase | SMT | 1 | PCS | PR37 |
| 3 | 55.64W02.MA5G | 64.49925.6DL | CHIP RES 49.9K F 1/16W 0402 | R2_SA;HF_SA;G_SA; | Released | TA-I ; RALEC ; CYNTEC ; YAGEO ; WALSIN | RM04FTN4992 ; RTT024992FTH ; RR0510S-4992-FN ; RC0402FR-0749K9L ; WR04X4992FTL | Multiple |  | Purchase | SMT | 1 | PCS | PR4 |
| 3 | 55.64W02.MA5G | 64.51015.6DL | CHIP RES 5.1K F 1/16W 0402 | R2_SA;HF_SA;G_SA; | Released | TA-I;RALEC;CYNTEC;YAGEO;WALSIN | RM04FTN5101 ; RTT025101FTH ; RR0510S-512-FN ; RC0402FR-075K1L;WR04X5101FTL | Multiple |  | Purchase | SMT | 2 | PCS | PR39 PR48 |
| 3 | 55.64W02.MA5G | 64.51025.6DL | CHIP RES 51K F 1/16W 0402 | R2_SA;HF_SA;G_SA; | Released | TA-I ; RALEC ; CYNTEC ; YAGEO;WALSIN | RM04FTN5102 ; RTT025102FTH ; RR0510S-513-FN ; RC0402FR-0751KL;WR04X5102FTL | Multiple |  | Purchase | SMT | 3 | PCS | PR33 PR34 PR46 |
| 3 | 55.64W02.MA5G | 64.51125.6DL | CHIP RES 51.1K F 1/16W 0402 | R2_SA;HF_SA;G_SA; | Released | TA-I;RALEC;CYNTEC;YAGEO;WALSIN | RM04FTN5112;RTT025112FTH;RR0510S-5112-FN;RC0402FR-0751K1L;WR04X5112FTL | Multiple |  | Purchase | SMT | 1 | PCS | PR3 |
| 3 | 55.64W02.MA5G | 64.54925.6DL | CHIP RES 54.9K F 1/16W 0402 | R2_SA;HF_SA;G_SA; | Released | TA-I ; RALEC ; CYNTEC ; YAGEO | RM04FTN5492 ; RTT025492FTH ; RR0510S-5492-FN ; RC0402FR-0754K9L | Multiple |  | Purchase | SMT | 1 | PCS | PR40 |
| 3 | 55.64W02.MA5G | 64.68115.6DL | CHIP RES 6.81K F 1/16W 0402 | R2_SA;HF_SA;G_SA; | Released | TAI;RALEC;CYNTEC;YAGEO | RM04FTN6811;RTT026811FTH;RR0510S-6811-FN; RC0402FR-076K81L | Multiple |  | Purchase | SMT | 4 | PCS | PR108 PR109 PR112 PR113 |
| 3 | 55.64W02.MA5G | 64.R0025.97L | CHIP RES 0.002 F 2W 2512 | R2_SA;HF_SA;G_SA; | Released | TAI;CYNTEC;WALSIN | RLM25FEER002;RL-3264-9-R002-FN;WW25RR002FTL | Multiple |  | Purchase | SMT | 4 | PCS | PR60 PR61 PR62 PR63 |
| 3 | 55.64W02.MA5G | 68.00217.561 | CHIP BEAD FCM1608CF-121T03 | R2_SA;HF_SA;G_SA; | Released | TAITECH | FCM1608CF-121T03 | Single |  | Purchase | SMT | 2 | PCS | L1 L2 |
| 3 | 55.64W02.MA5G | 68.2201D.10J | CHIP IND 22UH #A921CY-220M=P3 | R2_SA; | Released | TOKO | #A921CY-220M=P3 | Multiple |  | Purchase | SMT | 1 | PCS | PL7 |
| 3 | 55.64W02.MA5G | 71.07904.A0G | IC H/W MONI NCT7904D LQFP 48P | R2_SA; | Released | NUVOTON | NCT7904D | Single |  | Purchase | SMT | 1 | PCS | U1 |
| 3 | 55.64W02.MA5G | 71.09551.A0W | IC LED BLINK PCA9551PW-T TSSOP | R2_SA; | Released | NXP | PCA9551PW-T | Single |  | Purchase | SMT | 1 | PCS | U6 |
| 3 | 55.64W02.MA5G | 72.02464.00Q | IC EPROM 24LC64T-I/STG TSSOP8P | R2_SA; | Released | MICROCHIP | 24LC64T-I/STG | Single |  | Purchase | SMT | 1 | PCS | U5 |
| 3 | 55.64W02.MA5G | 73.01G32.AHH | IC CMOS 74LVC1G32GW SC70-5 | R2_SA;HF_SA;G_SA; | Released | NXP | 74LVC1G32GW | Single |  | Purchase | SMT | 3 | PCS | U10 U11 U3 |
| 3 | 55.64W02.MA5G | 73.07407.BHB | IC CMOS SN74LV07APWR TSSOP 14P | R2_SA; | Released | TI | SN74LV07APWR | Single |  | Purchase | SMT | 1 | PCS | U7 |
| 3 | 55.64W02.MA5G | 73.07474.BAB | IC CMOS 74AHC74PWR TSOOP 14P | R2_SA; | Released | TI | SN74AHC74PWR | Single |  | Purchase | SMT | 1 | PCS | U8 |
| 3 | 55.64W02.MA5G | 74.01276.B7Z | IC SWAP CTRL ADM1276-3ACPZ-RL LFCSP 20P | R2_SA; | Released | ADI | ADM1276-3ACPZ-RL | Single |  | Purchase | SMT | 1 | PCS | PU1 |
| 3 | 55.64W02.MA5G | 74.02490.A79 | IC PWR CTRL TPS2490DGSR MSOP10 | R2_SA; | Released | TI | TPS2490DGSR | Single |  | Purchase | SMT | 2 | PCS | PU6 PU7 |
| 3 | 55.64W02.MA5G | 74.07368.071 | IC PWM COMPARATOR NCT7368S SOP 8P | R2_SA; | Released | NUVOTON | NCT7368S | Single |  | Purchase | SMT | 1 | PCS | U2 |
| 3 | 55.64W02.MA5G | 74.08201.04P | IC DC/DC REGULATOR SY8201ABC SOT23-6 | R2_SA;HF_SA; | Released | SILERGY | SY8201ABC | Single |  | Purchase | SMT | 1 | PCS | U4 |
| 3 | 55.64W02.MA5G | 77.21561.00L | CHIP CAP POS 15U 25V 25TQC15M | R2_SA;HF_SA;G_SA; | Released | SANYO | 25TQC15M | Single |  | Purchase | SMT | 9 | PCS | TC12 TC13 TC14 TC15 TC16 TC17 TC18 TC4 TC8 |
| 3 | 55.64W02.MA5G | 77.26861.05L | CHIP CAP POS 68U 16V M7343 ESR | R2_SA; | Released | SANYO | 16TQC68MY | Multiple |  | Purchase | SMT | 9 | PCS | TC1 TC10 TC11 TC2 TC3 TC5 TC6 TC7 TC9 |
| 3 | 55.64W02.MA5G | 78.10322.2FL | CHIP CAP C 0.01U 25V K0402 X7R | R2_SA;HF_SA;G_SA; | Released | AVX;DARFON;MURATA;PHYCOMP;SAMSUNG;TAIYO;TDK;MURATA;YAGEO | 04023C103KAT2A;C1005X7R103KFT;GRM155R71E103KA01D;223891715636;CL05B103KA5NNNC;TMK105BJ103KV-F;C1005X7R1E103KT000F;WBM155R71E103KA01D;CC0402KRX7R8BB103 | Multiple |  | Purchase | SMT | 3 | PCS | PC5 PC85 PC86 |
| 3 | 55.64W02.MA5G | 78.10324.2BL | CHIP CAP C 0.01U 50V K0603 X7R | R2_SA;HF_SA;G_SA; | Released | AVX;KEMET;MURATA;PHYCOMP;SAMSUNG;TDK;DARFON;PANASONIC;WALSIN | 06035C103KAT2A;C0603C103K5RAC;GRM188R71H103KA01D;223858615636;CL10B103KB8NNNC;C1608X7R1H103KT;C1608X7R103KGT;ECJ1VB1H103K;0603B103K500CT | Multiple |  | Purchase | SMT | 2 | PCS | PC91 PC92 |
| 3 | 55.64W02.MA5G | 78.10421.2FL | CHIP CAP C 0.1U 16V K0402 X7R | R2_SA;HF_SA;G_SA; | Released | DARFON;MURATA;PHYCOMP;SAMSUNG;TAIYO;TDK;WALSIN;YAGEO | C1005X7R104KET;GRM155R71C104KA88D;223878715649;CL05B104KO5NNNC;EMK105BJ104KV-FR ;C1005X7R1C104KT000F;0402B104K160CT;CC0402KRX7R7BB104 | Multiple |  | Purchase | SMT | 6 | PCS | C2 C254 C256 C4 C5 PC41 |
| 3 | 55.64W02.MA5G | 78.10422.5FL | CHIP CAP C 0.1U 25V K0402 X5R | R2_SA;HF_SA;G_SA; | Released | MURATA;YAGEO;TDK;TAIYO;SAMSUNG;WALSIN;DARFON | GRM155R61E104KA87D;CC0402KRX5R8BB104;C1005X5R1E104KT000E;TMK105BJ104KV-F;CL05A104KA5NNNC;0402X104K250CT;C1005X5R104KFT | Multiple |  | Purchase | SMT | 4 | PCS | C51 C58 PC89 PC90 |
| 3 | 55.64W02.MA5G | 78.10424.2BL | CHIP CAP C 0.1U 50V K0603 X7R | R2_SA;HF_SA;G_SA; | Released | MURATA;TDK;AVX;PHYCOMP;SAMSUNG;DARFON;MATSUKI;WALSIN | GRM188R71H104KA93D;C1608X7R1H104KT000N;06035C104KAT2A;223858615649;CL10B104KB8NNNC;C1608X7R104KGT;MAG03X7R1H104K;0603B104K500CT | Multiple |  | Purchase | SMT | 17 | PCS | C10 C11 C14 C16 C20 C23 C24 C25 C31 C33 C39 C41 C47 C49 C52 C54 PC96 |
| 3 | 55.64W02.MA5G | 78.10521.2BL | CHIP CAP C 1U 16V K0603 X7R | R2_SA;HF_SA;G_SA; | Released | KEMET;MURATA;TAIYO;TDK;PHYCOMP;WALSIN;SAMSUNG;DARFON | C0603C105K4RAC;GRM188R71C105KA12D;EMK107B7105KA-T;C1608X7R1C105KT;223878615663;0603B105K160CT;CL10B105KO8NNNC;C1608X7R105KET | Multiple |  | Purchase | SMT | 7 | PCS | C12 C13 C15 C19 C53 C55 C9 |
| 3 | 55.64W02.MA5G | 78.10522.21L | CHIP CAP C 1U 25V K0805 X7R | R2_SA;HF_SA;G_SA; | Released | TAIYO;TDK;MURATA;SAMSUNG;DARFON;WALSIN | TMK212B7105KG-T;C2012X7R1E105KT;GRM21BR71E105KA99L;CL21B105KAFNNNE;C2012X7R105KFP;0805B105K250CT | Multiple |  | Purchase | SMT | 2 | PCS | PC10 PC9 |
| 3 | 55.64W02.MA5G | 78.10522.5BL | CHIP CAP C 1U 25V K0603 X5R | R2_SA;HF_SA;G_SA; | Released | MURATA;TDK;PHYCOMP;TAIYO;MATSUKI;DARFON;TDK;WALSIN;SAMSUNG;YAGEO | GRM188R61E105KA12D;C1608X5R1E105KT000N;223891613663;TMK107BJ105KA-T;MAG03X5R1E105K;C1608X5R105KFT;C1608X5R1E105KT000N;0603X105K250CT;CL10A105KA8NNNC;CC0603KRX5R8BB105 | Multiple |  | Purchase | SMT | 11 | PCS | C257 C258 C26 C32 C34 C40 C42 C48 C50 PC1 PC4 |
| 3 | 55.64W02.MA5G | 78.10621.22L | CHIP CAP C 10U 16V K1206 X7R | R2_SA;HF_SA;G_SA; | Released | MURATA;TDK;AVX;DARFON;SAMSUNG;TAIYO | GRM31CR71C106KA12L;C3216X7R1C106KT;CM316X7R106K16AT;C3216X7R106KEP;CL31B106KOHNNNE;EMK316B7106KL-T | Multiple |  | Purchase | SMT | 1 | PCS | PC1262 |
| 3 | 55.64W02.MA5G | 78.10622.51L | CHIP CAP C 10U 25V K0805 X5R | R2_SA;HF_SA;G_SA; | Released | MATSUKI;SAMSUNG;TAIYO;AVX;MURATA;TDK;YAGEO | MAG05X5R1E106K;CL21A106KAYNNNE;TMK212BJ106KG-TD;CM21X5R106K25AT;GRM21BR61E106KA73L;C2012X5R1E106KT;CC0805KKX5R8BB106 | Multiple |  | Purchase | SMT | 4 | PCS | C1 C3 PC2 PC95 |
| 3 | 55.64W02.MA5G | 78.10622.52L | CHIP CAP C 10U 25V K1206 X5R | R2_SA;HF_SA;G_SA; | Released | TAIYO;MURATA;AVX;TDK;KEMET;MATSUKI;PHYCOMP;DARFON;SAMSUNG | TMK316BJ106KL-T;GRM31CR61E106KA12L;12063D106KAT2A;C3216X5R1E106KT;C1206C106K3PAC;MAG06X5R1E106K;222291113676;C3216X5R106KFP;CL31A106KAHNNNE | Multiple |  | Purchase | SMT | 1 | PCS | C259 |
| 3 | 55.64W02.MA5G | 78.22034.1BL | CHIP CAP 22P50V J0603 NPO(ROHS | R2_SA;HF_SA;G_SA; | Released | PHYCOMP;MURATA;AVX;TDK;SAMSUNG;DARFON;WALSIN | 223886715229;GRM1885C1H220JA01D;06035A220JAT2A;C1608C0G1H220JT;CL10C220JB8NNNC;C1608NPO220JGT;0603N220J500LT | Multiple |  | Purchase | SMT | 1 | PCS | PC42 |
| 3 | 55.64W02.MA5G | 78.22124.2FL | CHIP CAP C 220P 50V K0402 X7R | R2_SA;HF_SA;G_SA; | Released | MURATA;AVX;TAIYO;PHYCOMN;DARFON | GRM155R71H221KA01D;04025C221KAT2A;UMK105BJ221KV-F;223858715614;C1005X7R221KGT | Multiple |  | Purchase | SMT | 4 | PCS | PC87 PC88 PC93 PC94 |
| 3 | 55.64W02.MA5G | 78.22224.2FL | CHIP CAP C 2200P 50V K0402 X7R | R2_SA;HF_SA;G_SA; | Released | MURATA;AVX;TDK;TAIYO;PHYCOMP;DARFON;SAMSUNG;WALSIN;YAGEO | GRM155R71H222KA01D;04025C222KAT2A;C1005X7R1H222KT000F;UMK105BJ222KV-F;223858715627;C1005X7R222KGT;CL05B222KB5NNNC;0402B222K500CT;CC0402KRX7R9BB222 | Multiple |  | Purchase | SMT | 2 | PCS | C7 C8 |
| 3 | 55.64W02.MA5G | 78.22324.2BL | CHIP CAP C .022U 50V K0603 X7R | R2_SA;HF_SA;G_SA; | Released | MURATA;PHYCOMP;SAMSUNG;TDK;DARFON | GRM188R71H223KA01D;223858615641;CL10B223KB8NNNC;C1608X7R1H223KT;C1608X7R223KGT | Multiple |  | Purchase | SMT | 1 | PCS | PC6 |
| 3 | 55.64W02.MA5G | 78.22611.52L | CHIP CAP 22U 16V M1206 X5R | R2_SA;HF_SA;G_SA; | Released | MURATA;TAIYO;AVX;SAMSUNG | GRM31CR61C226ME15L;EMK316BJ226ML-T;CM316X5R226M16AT;CL31A226KOHNNNE | Multiple |  | Purchase | SMT | 1 | PCS | PC43 |
| 3 | 55.64W02.MA5G | 78.47510.5FL | CHIP CAP C 4.7U 6.3V M0402 X5R | R2_SA;HF_SA;G_SA; | Released | SAMSUNG;TAIYO;MURATA;AVX;YAGEO;WALSIN;DARFON;TDK | CL05A475MQ5NRNC;JDK105BJ475MV-F;GRM155R60J475ME87D;CV05X5R475M06AH065;CC0402MRX5R5BB475;0402X475M6R3CT;C1005X5R475MCT;C1005X5R0J475KT | Multiple |  | Purchase | SMT | 1 | PCS | C6 |
| 3 | 55.64W02.MA5G | 78.47520.5BL | CHIP CAP C 4.7U 6.3V K0603 X5R | R2_SA;HF_SA;G_SA; | Released | MURATA;AVX;PHYCOMP;TAIYO;PANASONIC;TDK;MATSUKI;SAMSUNG;DARFON | GRM188R60J475KE19D;06036D475KAT2A;225520613672;JMK107BJ475KAT;ECJ1VB0J475K;C1608X5R0J475KT;MAG03X5R0J475K;CL10A475KQ8NNNC;C1608X5R475KCT | Multiple |  | Purchase | SMT | 1 | PCS | C253 |
| 3 | 55.64W02.MA5G | 78.47524.L2L | CHIP CAP C 4.7UF 50V K1206 X5R T=0.9 | R2_SA;HF_SA;G_SA; | Released | MURATA;SAMSUNG;TAIYO | GRM319R61H475KA12D;CL31A475KB9LNNC;UMK316BJ475KD-T | Multiple |  | Purchase | SMT | 1 | PCS | PC40 |
| 3 | 55.64W02.MA5G | 82.20034.191 | OSC 33M 3.3V 50PPM HXO-56B SMD | R2_SA; | Released | HOSONIC | D56B33.0000MNS | Single |  | Purchase | SMT | 1 | PCS | OSC1 |
| 3 | 55.64W02.MA5G | 83.00015.0AD | DIODE TVS SMCJ15A SMC | R2_SA; | Released | DIODES | SMCJ15A | Single |  | Purchase | SMT | 1 | PCS | PD2 |
| 3 | 55.64W02.MA5G | 83.00016.A1H | DIODE SW BAS16H 100VSOD123F(GP | R2_SA;G_SA; | Released | NXP | BAS16H | Single |  | Purchase | SMT | 12 | PCS | D1 D10 D11 D12 D2 D3 D4 D5 D6 D7 D8 D9 |
| 3 | 55.64W02.MA5G | 83.1S380.01F | DIODE SW 1SS380TE-17 SOD-323 | R2_SA; | Released | ROHM | 1SS380TE-17 | Single |  | Purchase | SMT | 1 | PCS | D19 |
| 3 | 55.64W02.MA5G | 83.3R004.B8D | DIODE S.B MBRS340T3G 40V3A SMC | R2_SA; | Released | ON | MBRS340T3G | Single |  | Purchase | SMT | 3 | PCS | D14 D15 D16 |
| 3 | 55.64W02.MA5G | 83.3R903.03G | DIODE ZEN 3.9V BZG05C3V9 DO214AC | R2_SA; | Released | VISHAY | BZG05C3V9 | Single |  | Purchase | SMT | 1 | PCS | D13 |
| 3 | 55.64W02.MA5G | 83.R0304.B3F | DIODE CH751H-40PT 40V0.03A | R_SA; | Obsoleted | CHENMKO | CH751H-40PT | Single |  | Purchase | SMT | 1 | PCS | D18 |
| 3 | 55.64W02.MA5G | 84.03904.L06 | XTOR PMBS3904 NPN SOT23 (GP) | R2_SA;HF_SA;G_SA; | Released | NXP | PMBS3904 | Multiple |  | Purchase | SMT | 13 | PCS | PQ10 PQ14 PQ5 PQ6 PQ9 Q1 Q2 Q3 Q4 Q5 Q6 Q7 Q8 |
| 3 | 55.64W02.MA5G | 84.03906.R11 | XTOR MMBT3906 PNP SOT-23 | R2_SA;HF_SA;G_SA; | Released | PANJIT | MMBT3906 | Single |  | Purchase | SMT | 1 | PCS | PQ4 |
| 3 | 55.64W02.MA5G | 84.27002.C3F | FET MOS 2N7002DW-7-F NC SOT363 | R2_SA;HF_SA; | Released | DIODES | 2N7002DW-7-F | Single |  | Purchase | SMT | 1 | PCS | Q10 |
| 3 | 55.64W02.MA5G | 84.27002.W31 | FET MOS 2N7002 NC SOT-23 | R2_SA;HF_SA;G_SA; | Released | PANJIT | 2N7002 | Single |  | Purchase | SMT | 1 | PCS | Q49 |
| 2 | 55.64W02.A21G | 86.00Q43.140 | SCRW NUT HEX M3 | R_SA;G_SA; | Released | TBD |  | Single |  | Purchase | DIP | 4 | PCS |  |
| 2 | 55.64W02.A21G | 86.1A524.100 | SCRW MACH PAN M3*10L | R_SA; | Released | TBD |  | Single |  | Purchase | DIP | 4 | PCS |  |
| 2 | 55.64W02.A21G | 86.HA574.5R0 | SCRW PAN T3 L5 | R2_SA; | Released | TBD |  | Single |  | Purchase | DIP | 12 | PCS |  |
| 2 | 55.64W02.A21G | 88.10301.405 | WASH PLASTIC WS-1C | R2_SA; | Released | TBD |  | Single |  | Purchase | DIP | 12 | PCS |  |
| 1 | 91.64W10.A31G | DP.64W10.A03 | PACKING FOR KNOX FAN CONTROLLER BOARD | N/A; | Released |  |  |  | M | Manufacture |  | 1 | PCS |  |
| 2 | DP.64W10.A03 | 38.09008.001 | DESICANT SILICA GEL 30G H25 | R2_SA; | Released | TBD |  | Single |  | Purchase |  | 1 | PCS |  |
| 2 | DP.64W10.A03 | 40.54T01.001 | LBL CAUTION FOR P97AE | R2_SA;G_SA; | Released | CHENGMAY | 40.54T01.001 | Single |  | Purchase |  | 1 | PCS |  |
| 2 | DP.64W10.A03 | 42.5I405.001 | BAG PE ESD 140*550MM | R2_SA; | Released | TBD |  | Single |  | Purchase |  | 1 | PCS |  |
| 2 | DP.64W10.A03 | 42.60X01.001 | BAG ZIP 320*230MM | R2_SA; | Released | HONGWANG;WINGFUNG | 42.60X01.001 | Multiple |  | Purchase |  | 3.1E-2 | PCS |  |
| 2 | DP.64W10.A03 | 44.5P305.011 | CTN AB B/R 490*390*554MM | R2_SA; | Released | TBD |  | Single |  | Purchase |  | 3.1300000000000001E-2 | PCS |  |
| 2 | DP.64W10.A03 | 45.00005.312 | LBL CTN ART 124*40 B/W ALL | R2_SA;G_SA; | Released | CHENGMAY | 45.00005.312 | Single |  | Purchase |  | 3.1E-2 | PCS |  |
| 2 | DP.64W10.A03 | 45.3B201.001 | LBL CTN 101.6X152.4 H100-ASTRO | R2_SA;HF_SA; | Released | ZHENFENG |  | Single |  | Purchase |  | 3.1300000000000001E-2 | PCS |  |
| 2 | DP.64W10.A03 | 46.30S02.001 | CORNER KRAFT PAPER 900*50*50*3 | R2_SA;HF_SA;G_SA; | Released | KHL;SAFEWAY | 46.30S02.001 | Multiple |  | Purchase |  | 3.5000000000000001E-3 | PCS |  |
| 2 | DP.64W10.A03 | 46.58F01.001 | CORNER PAPER1100*50*50*3 ORIGI | R2_SA;G_SA; | Released | COPLASCO;MYS | 46.58F01.001 | Multiple |  | Purchase |  | 3.5000000000000001E-3 | PCS |  |
| 2 | DP.64W10.A03 | 46.60A03.001 | SHEET AB FLUTE 1200*1000 NS110 | R2_SA;G_SA; | Released | GINYOUNG;TRICAN | 46.60A03.001 | Multiple |  | Purchase |  | 1.8E-3 | PCS |  |
| 2 | DP.64W10.A03 | 46.67E01.001 | CORNER PAPER 1520*50*50*5MM | R2_SA; | Released | TBD |  | Single |  | Purchase |  | 7.0000000000000001E-3 | PCS |  |
| 2 | DP.64W10.A03 | 47.54Z11.001 | CSN PAD EPE 475*375*15MM | R2_SA; | Released | TRICAN | Void | Single |  | Purchase |  | 6.25E-2 | PCS |  |
| 2 | DP.64W10.A03 | 47.57S22.001 | PALLET PLYWOOD 1200*1000*114MM | R2_SA; | Released | JIAMAO | Void | Single |  | Purchase |  | 1.8E-3 | PCS |  |
| 2 | DP.64W10.A03 | 47.5I308.001 | P-PAD AB 479*50MM | R2_SA; | Released | TBD |  | Single |  | Purchase |  | 6.25E-2 | PCS |  |
| 2 | DP.64W10.A03 | 47.5I510.001 | P-PAD AB 380*58MM | R2_SA; | Released | TBD |  | Single |  | Purchase |  | 6.25E-2 | PCS |  |
| 2 | DP.64W10.A03 | 47.5P333.001 | PARTITION A 479*506MM | R2_SA; | Released | TBD |  | Single |  | Purchase |  | 0.15629999999999999 | PCS |  |
| 2 | DP.64W10.A03 | 47.64W05.001 | CSN PARTITION A 506*375MM | R2_SA; | Released | TBD |  | Single |  | Purchase |  | 0.28129999999999999 | PCS |  |
